FILE_TYPE=LIBRARY_PARTS;
primitive 'CONN4_D42317002','CONN4_D42317002_THMT','CONN4_D42317002_PIP';
pin
    'IO1':
      PIN_NUMBER='(1)';
      BIDIRECTIONAL='TRUE';
      INPUT_LOAD='(-0.01,0.01)';
      OUTPUT_LOAD='(1.0,-1.0)';
    'IO2':
      PIN_NUMBER='(2)';
      BIDIRECTIONAL='TRUE';
      INPUT_LOAD='(-0.01,0.01)';
      OUTPUT_LOAD='(1.0,-1.0)';
    'IO3':
      PIN_NUMBER='(3)';
      BIDIRECTIONAL='TRUE';
      INPUT_LOAD='(-0.01,0.01)';
      OUTPUT_LOAD='(1.0,-1.0)';
    'IO4':
      PIN_NUMBER='(4)';
      BIDIRECTIONAL='TRUE';
      INPUT_LOAD='(-0.01,0.01)';
      OUTPUT_LOAD='(1.0,-1.0)';
  end_pin;
  body
    PART_NAME='CONN4_D42317002';
    PHYS_DES_PREFIX='J';
  end_body;
end_primitive;

END.
